# BASEBOARD_FAB2 (Tioga Pass) — schematic netlist excerpt (pin names and nets, part order shuffled) for the footprints in the layout excerpt that follows; sources: Cadence DE-HDL packaged netlist, KiCad conversion of Wiwynn_Tioga_Pass_MB.brd

R3L14  RES  68.1K 1% EMPTY  pkg 0402  page 236 : A = VR_P1V05_PCH_STBY_OCSET ; B = GND
R6W5  RES  4.75K 1% CHIP  pkg 0402  page 247 : A = P3V3_STBY ; B = PCA9555_A1
R9M5  RES  100.0K 1% EMPTY  pkg 0402  page 226 : A = P3V3_STBY ; B = VR_PVDDQ_KLM_VREN

(kicad_pcb
	(version 20260206)
	(generator "pcbnew")
	(generator_version "10.0")
	(general
		(thickness 1.6)
		(legacy_teardrops no)
	)
	(paper "A4")
	(title_block
		(title "Wiwynn_Tioga_Pass_MB.brd")
		(comment 1 "Tioga Pass / footprints 3797-3799 of 4770")
	)
	(layers
		(0 "F.Cu" signal "TOP")
		(4 "In1.Cu" signal "L2GND")
		(6 "In2.Cu" signal "L3")
		(8 "In3.Cu" signal "L4GND")
		(10 "In4.Cu" signal "L5")
		(12 "In5.Cu" signal "L6GND")
		(14 "In6.Cu" signal "L7VCC")
		(16 "In7.Cu" signal "L8VCC")
		(18 "In8.Cu" signal "L9GND")
		(20 "In9.Cu" signal "L10")
		(22 "In10.Cu" signal "L11GND")
		(24 "In11.Cu" signal "L12")
		(26 "In12.Cu" signal "L13GND")
		(2 "B.Cu" signal "BOTTOM")
		(9 "F.Adhes" user "F.Adhesive")
		(11 "B.Adhes" user "B.Adhesive")
		(13 "F.Paste" user "Package Geometry/Pastemask Top")
		(15 "B.Paste" user "Package Geometry/Pastemask Bottom")
		(5 "F.SilkS" user "Ref Des/Silkscreen Top")
		(7 "B.SilkS" user "Ref Des/Silkscreen Bottom")
		(1 "F.Mask" user "Board Geometry/Soldermask Top")
		(3 "B.Mask" user "Board Geometry/Soldermask Bottom")
		(17 "Dwgs.User" user "User.Drawings")
		(19 "Cmts.User" user "User.Comments")
		(21 "Eco1.User" user "User.Eco1")
		(23 "Eco2.User" user "User.Eco2")
		(25 "Edge.Cuts" user "Board Geometry/Outline")
		(27 "Margin" user)
		(31 "F.CrtYd" user "Package Geometry/Place Bound Top")
		(29 "B.CrtYd" user "Package Geometry/Place Bound Bottom")
		(35 "F.Fab" user "Ref Des/Assembly Top")
		(33 "B.Fab" user "Ref Des/Assembly Bottom")
	)
	(footprint ""
		(layer "B.Cu")
		(at 384.0734 -156.569664 -90)
		(property "Reference" "R3L14"
			(at 0 0 90)
			(layer "B.SilkS")
			(hide yes)
			(effects
				(font
					(size 1.27 1.27)
				)
				(justify mirror)
			)
		)
		(property "Value" ""
			(at 0 0 90)
			(layer "B.Fab")
			(effects
				(font
					(size 1.27 1.27)
				)
				(justify mirror)
			)
		)
		(duplicate_pad_numbers_are_jumpers no)
		(fp_poly
			(pts
				(xy 0.2794 -0.1016) (xy -0.2794 -0.1016) (xy -0.2794 0.9906) (xy 0.2794 0.9906)
			)
			(stroke
				(width 0)
				(type default)
			)
			(fill no)
			(layer "B.CrtYd")
		)
		(fp_line
			(start -0.2794 0.9906)
			(end -0.2794 -0.1016)
			(stroke
				(width 0.1)
				(type default)
			)
			(layer "B.Fab")
		)
		(fp_line
			(start 0.2794 0.9906)
			(end -0.2794 0.9906)
			(stroke
				(width 0.1)
				(type default)
			)
			(layer "B.Fab")
		)
		(fp_line
			(start -0.2794 -0.1016)
			(end 0.2794 -0.1016)
			(stroke
				(width 0.1)
				(type default)
			)
			(layer "B.Fab")
		)
		(fp_line
			(start 0.2794 -0.1016)
			(end 0.2794 0.9906)
			(stroke
				(width 0.1)
				(type default)
			)
			(layer "B.Fab")
		)
		(pad "1" smd rect
			(at 0 0 90)
			(size 0.508 0.508)
			(layers "B.Cu" "B.Mask" "B.Paste")
			(net "VR_P1V05_PCH_STBY_OCSET")
		)
		(pad "2" smd rect
			(at 0 0.889 90)
			(size 0.508 0.508)
			(layers "B.Cu" "B.Mask" "B.Paste")
			(net "GND")
		)
		(zone
			(layer "B.Cu")
			(hatch none 0.5)
			(connect_pads
				(clearance 0)
			)
			(min_thickness 0.25)
			(keepout
				(tracks not_allowed)
				(vias allowed)
				(pads allowed)
				(copperpour not_allowed)
				(footprints allowed)
			)
			(placement
				(enabled no)
				(sheetname "")
			)
			(fill
				(thermal_gap 0.5)
				(thermal_bridge_width 0.5)
				(island_removal_mode 0)
			)
			(polygon
				(pts
					(xy 383.4384 -156.315664) (xy 383.4384 -156.823664) (xy 383.8194 -156.823664) (xy 383.8194 -156.315664)
				)
			)
		)
		(zone
			(layer "B.Cu")
			(hatch none 0.5)
			(connect_pads
				(clearance 0)
			)
			(min_thickness 0.25)
			(keepout
				(tracks allowed)
				(vias not_allowed)
				(pads allowed)
				(copperpour not_allowed)
				(footprints allowed)
			)
			(placement
				(enabled no)
				(sheetname "")
			)
			(fill
				(thermal_gap 0.5)
				(thermal_bridge_width 0.5)
				(island_removal_mode 0)
			)
			(polygon
				(pts
					(xy 383.8194 -156.315664) (xy 383.8194 -156.823664) (xy 383.4384 -156.823664) (xy 383.4384 -156.315664)
				)
			)
		)
	)
	(footprint ""
		(layer "B.Cu")
		(at 482.131116 -144.771872 -90)
		(property "Reference" "R6W5"
			(at 0.8382 -0.67818 270)
			(unlocked yes)
			(layer "B.SilkS")
			(effects
				(font
					(size 0.4064 0.254)
					(thickness 0.1524)
				)
				(justify left mirror)
			)
		)
		(property "Value" ""
			(at 0 0 90)
			(layer "B.Fab")
			(effects
				(font
					(size 1.27 1.27)
				)
				(justify mirror)
			)
		)
		(duplicate_pad_numbers_are_jumpers no)
		(fp_poly
			(pts
				(xy 0.2794 -0.1016) (xy -0.2794 -0.1016) (xy -0.2794 0.9906) (xy 0.2794 0.9906)
			)
			(stroke
				(width 0)
				(type default)
			)
			(fill no)
			(layer "B.CrtYd")
		)
		(fp_line
			(start -0.2794 0.9906)
			(end -0.2794 -0.1016)
			(stroke
				(width 0.1)
				(type default)
			)
			(layer "B.Fab")
		)
		(fp_line
			(start 0.2794 0.9906)
			(end -0.2794 0.9906)
			(stroke
				(width 0.1)
				(type default)
			)
			(layer "B.Fab")
		)
		(fp_line
			(start -0.2794 -0.1016)
			(end 0.2794 -0.1016)
			(stroke
				(width 0.1)
				(type default)
			)
			(layer "B.Fab")
		)
		(fp_line
			(start 0.2794 -0.1016)
			(end 0.2794 0.9906)
			(stroke
				(width 0.1)
				(type default)
			)
			(layer "B.Fab")
		)
		(pad "1" smd rect
			(at 0 0 90)
			(size 0.508 0.508)
			(layers "B.Cu" "B.Mask" "B.Paste")
			(net "P3V3_STBY")
		)
		(pad "2" smd rect
			(at 0 0.889 90)
			(size 0.508 0.508)
			(layers "B.Cu" "B.Mask" "B.Paste")
			(net "PCA9555_A1")
		)
		(zone
			(layer "B.Cu")
			(hatch none 0.5)
			(connect_pads
				(clearance 0)
			)
			(min_thickness 0.25)
			(keepout
				(tracks not_allowed)
				(vias allowed)
				(pads allowed)
				(copperpour not_allowed)
				(footprints allowed)
			)
			(placement
				(enabled no)
				(sheetname "")
			)
			(fill
				(thermal_gap 0.5)
				(thermal_bridge_width 0.5)
				(island_removal_mode 0)
			)
			(polygon
				(pts
					(xy 481.496116 -144.517872) (xy 481.496116 -145.025872) (xy 481.877116 -145.025872) (xy 481.877116 -144.517872)
				)
			)
		)
		(zone
			(layer "B.Cu")
			(hatch none 0.5)
			(connect_pads
				(clearance 0)
			)
			(min_thickness 0.25)
			(keepout
				(tracks allowed)
				(vias not_allowed)
				(pads allowed)
				(copperpour not_allowed)
				(footprints allowed)
			)
			(placement
				(enabled no)
				(sheetname "")
			)
			(fill
				(thermal_gap 0.5)
				(thermal_bridge_width 0.5)
				(island_removal_mode 0)
			)
			(polygon
				(pts
					(xy 481.877116 -144.517872) (xy 481.877116 -145.025872) (xy 481.496116 -145.025872) (xy 481.496116 -144.517872)
				)
			)
		)
	)
	(footprint ""
		(layer "B.Cu")
		(at -0.127 -132.334)
		(property "Reference" "R9M5"
			(at 0 0 0)
			(layer "B.SilkS")
			(hide yes)
			(effects
				(font
					(size 1.27 1.27)
				)
				(justify mirror)
			)
		)
		(property "Value" ""
			(at 0 0 0)
			(layer "B.Fab")
			(effects
				(font
					(size 1.27 1.27)
				)
				(justify mirror)
			)
		)
		(duplicate_pad_numbers_are_jumpers no)
		(fp_poly
			(pts
				(xy 0.2794 -0.1016) (xy -0.2794 -0.1016) (xy -0.2794 0.9906) (xy 0.2794 0.9906)
			)
			(stroke
				(width 0)
				(type default)
			)
			(fill no)
			(layer "B.CrtYd")
		)
		(fp_line
			(start -0.2794 -0.1016)
			(end 0.2794 -0.1016)
			(stroke
				(width 0.1)
				(type default)
			)
			(layer "B.Fab")
		)
		(fp_line
			(start -0.2794 0.9906)
			(end -0.2794 -0.1016)
			(stroke
				(width 0.1)
				(type default)
			)
			(layer "B.Fab")
		)
		(fp_line
			(start 0.2794 -0.1016)
			(end 0.2794 0.9906)
			(stroke
				(width 0.1)
				(type default)
			)
			(layer "B.Fab")
		)
		(fp_line
			(start 0.2794 0.9906)
			(end -0.2794 0.9906)
			(stroke
				(width 0.1)
				(type default)
			)
			(layer "B.Fab")
		)
		(pad "1" smd rect
			(at 0 0 180)
			(size 0.508 0.508)
			(layers "B.Cu" "B.Mask" "B.Paste")
			(net "P3V3_STBY")
		)
		(pad "2" smd rect
			(at 0 0.889 180)
			(size 0.508 0.508)
			(layers "B.Cu" "B.Mask" "B.Paste")
			(net "VR_PVDDQ_KLM_VREN")
		)
		(zone
			(layer "B.Cu")
			(hatch none 0.5)
			(connect_pads
				(clearance 0)
			)
			(min_thickness 0.25)
			(keepout
				(tracks allowed)
				(vias not_allowed)
				(pads allowed)
				(copperpour not_allowed)
				(footprints allowed)
			)
			(placement
				(enabled no)
				(sheetname "")
			)
			(fill
				(thermal_gap 0.5)
				(thermal_bridge_width 0.5)
				(island_removal_mode 0)
			)
			(polygon
				(pts
					(xy 0.127 -132.08) (xy -0.381 -132.08) (xy -0.381 -131.699) (xy 0.127 -131.699)
				)
			)
		)
		(zone
			(layer "B.Cu")
			(hatch none 0.5)
			(connect_pads
				(clearance 0)
			)
			(min_thickness 0.25)
			(keepout
				(tracks not_allowed)
				(vias allowed)
				(pads allowed)
				(copperpour not_allowed)
				(footprints allowed)
			)
			(placement
				(enabled no)
				(sheetname "")
			)
			(fill
				(thermal_gap 0.5)
				(thermal_bridge_width 0.5)
				(island_removal_mode 0)
			)
			(polygon
				(pts
					(xy 0.127 -131.699) (xy -0.381 -131.699) (xy -0.381 -132.08) (xy 0.127 -132.08)
				)
			)
		)
	)
)
